#ISCELL
  mstr_misc dns *
  *
#ISCELL
  pure_quanta quanta_title_block_c *
  *
#ISCELL
  standard offpage *
  page240_i1
#ISCELL
  standard offpage *
  page240_i10
#CELL
  pure_quanta q_res_4p_12 *
  page240_i11
#ISCELL
  standard offpage *
  page240_i12
#ISCELL
  logical_power universal_power *
  page240_i13
#ISCELL
  logical_power universal_gnd *
  page240_i14
#CELL
  pure_quanta q_cap *
  page240_i15
#CELL
  pure_quanta q_res *
  page240_i16
#ISCELL
  logical_power universal_gnd *
  page240_i17
#CELL
  pure_quanta q_res *
  page240_i18
#CELL
  pure_quanta q_res *
  page240_i19
#ISCELL
  logical_power universal_power *
  page240_i2
#ISCELL
  standard offpage *
  page240_i20
#ISCELL
  standard offpage *
  page240_i21
#CELL
  pure_quanta ina183a1idbvr *
  page240_i22
#ISCELL
  logical_power universal_gnd *
  page240_i23
#ISCELL
  standard offpage *
  page240_i24
#ISCELL
  standard offpage *
  page240_i25
#ISCELL
  standard offpage *
  page240_i26
#ISCELL
  logical_power universal_gnd *
  page240_i28
#CELL
  pure_quanta ina183a1idbvr *
  page240_i29
#CELL
  pure_quanta q_res_4p_12 *
  page240_i3
#ISCELL
  logical_power universal_gnd *
  page240_i30
#ISCELL
  standard offpage *
  page240_i31
#ISCELL
  logical_power universal_gnd *
  page240_i32
#CELL
  pure_quanta q_cap *
  page240_i33
#ISCELL
  logical_power universal_power *
  page240_i34
#CELL
  pure_quanta q_res *
  page240_i35
#ISCELL
  logical_power universal_power *
  page240_i36
#CELL
  pure_quanta q_res *
  page240_i37
#CELL
  pure_quanta q_res *
  page240_i38
#CELL
  pure_quanta ina230airgtr *
  page240_i39
#ISCELL
  logical_power universal_power *
  page240_i4
#ISCELL
  standard offpage *
  page240_i5
#ISCELL
  standard offpage *
  page240_i6
#ISCELL
  logical_power universal_power *
  page240_i7
#ISCELL
  standard offpage *
  page240_i8
#ISCELL
  standard offpage *
  page240_i9
